(kicad_pcb
	(version 20241229)
	(generator "pcbnew")
	(generator_version "9.0")
	(general
		(thickness 1.61)
		(legacy_teardrops no)
	)
	(paper "A3")
	(title_block
		(title "RDIMM DDR5 Tester")
		(date "2026-05-21")
		(rev "2.2.0")
		(company "Antmicro")
		(comment 9 "footprints 464-468 of 796")
	)
	(layers
		(0 "F.Cu" signal)
		(4 "In1.Cu" power)
		(6 "In2.Cu" mixed)
		(8 "In3.Cu" power)
		(10 "In4.Cu" mixed)
		(12 "In5.Cu" power)
		(14 "In6.Cu" mixed)
		(16 "In7.Cu" power)
		(18 "In8.Cu" power)
		(20 "In9.Cu" mixed)
		(22 "In10.Cu" power)
		(2 "B.Cu" signal)
		(9 "F.Adhes" user "F.Adhesive")
		(11 "B.Adhes" user "B.Adhesive")
		(13 "F.Paste" user)
		(15 "B.Paste" user)
		(5 "F.SilkS" user "F.Silkscreen")
		(7 "B.SilkS" user "B.Silkscreen")
		(1 "F.Mask" user)
		(3 "B.Mask" user)
		(17 "Dwgs.User" user "User.Drawings")
		(19 "Cmts.User" user "User.Comments")
		(21 "Eco1.User" user "User.Eco1")
		(23 "Eco2.User" user "User.Eco2")
		(25 "Edge.Cuts" user)
		(27 "Margin" user)
		(31 "F.CrtYd" user "F.Courtyard")
		(29 "B.CrtYd" user "B.Courtyard")
		(35 "F.Fab" user)
		(33 "B.Fab" user)
	)
	(footprint "antmicro-footprints:C_0603_1608Metric"
		(layer "B.Cu")
		(at 148.275 192.625 180)
		(descr "Capacitor SMD 0603")
		(tags "capacitor 0603")
		(property "Reference" "C224"
			(at -4.045 -0.595 0)
			(layer "B.SilkS")
			(effects
				(font
					(size 0.7 0.7)
					(thickness 0.15)
				)
				(justify left bottom mirror)
			)
		)
		(property "Value" "C_10u_25V_0603"
			(at -1.42757 -1.770288 0)
			(layer "B.Fab")
			(effects
				(font
					(size 0.7 0.7)
					(thickness 0.15)
				)
				(justify left bottom mirror)
			)
		)
		(property "Datasheet" "https://product.tdk.com/en/search/capacitor/ceramic/mlcc/info?part_no=C1608X5R1E106M080AC"
			(at 0 0 180)
			(layer "F.Fab")
			(hide yes)
			(effects
				(font
					(size 1.27 1.27)
					(thickness 0.15)
				)
			)
		)
		(property "MPN" "C1608X5R1E106M080AC"
			(at 0 0 180)
			(unlocked yes)
			(layer "B.Fab")
			(hide yes)
			(effects
				(font
					(size 1 1)
					(thickness 0.15)
				)
				(justify mirror)
			)
		)
		(property "Manufacturer" "TDK"
			(at 0 0 180)
			(unlocked yes)
			(layer "B.Fab")
			(hide yes)
			(effects
				(font
					(size 1 1)
					(thickness 0.15)
				)
				(justify mirror)
			)
		)
		(property "License" "Apache-2.0"
			(at 0 0 180)
			(unlocked yes)
			(layer "B.Fab")
			(hide yes)
			(effects
				(font
					(size 1 1)
					(thickness 0.15)
				)
				(justify mirror)
			)
		)
		(property "Author" "Antmicro"
			(at 0 0 180)
			(unlocked yes)
			(layer "B.Fab")
			(hide yes)
			(effects
				(font
					(size 1 1)
					(thickness 0.15)
				)
				(justify mirror)
			)
		)
		(property "Val" "10u"
			(at 0 0 180)
			(unlocked yes)
			(layer "B.Fab")
			(hide yes)
			(effects
				(font
					(size 1 1)
					(thickness 0.15)
				)
				(justify mirror)
			)
		)
		(property "Voltage" "25V"
			(at 0 0 180)
			(unlocked yes)
			(layer "B.Fab")
			(hide yes)
			(effects
				(font
					(size 1 1)
					(thickness 0.15)
				)
				(justify mirror)
			)
		)
		(property "Dielectric" ""
			(at 0 0 180)
			(unlocked yes)
			(layer "B.Fab")
			(hide yes)
			(effects
				(font
					(size 1 1)
					(thickness 0.15)
				)
				(justify mirror)
			)
		)
		(sheetname "/PCIe connector/")
		(sheetfile "pcie-connector.kicad_sch")
		(attr smd)
		(fp_line
			(start -0.15 0.4)
			(end 0.15 0.4)
			(stroke
				(width 0.15)
				(type solid)
			)
			(layer "B.SilkS")
		)
		(fp_line
			(start -0.15 -0.4)
			(end 0.15 -0.4)
			(stroke
				(width 0.15)
				(type solid)
			)
			(layer "B.SilkS")
		)
		(fp_rect
			(start -1.25 0.65)
			(end 1.25 -0.65)
			(stroke
				(width 0.05)
				(type solid)
			)
			(fill no)
			(layer "B.CrtYd")
		)
		(fp_rect
			(start -0.8 0.4)
			(end 0.8 -0.4)
			(stroke
				(width 0.15)
				(type solid)
			)
			(fill no)
			(layer "B.Fab")
		)
		(fp_text user "${REFERENCE}"
			(at -1.682 -3.895 0)
			(layer "B.Fab")
			(effects
				(font
					(size 0.7 0.7)
					(thickness 0.15)
				)
				(justify left bottom mirror)
			)
		)
		(fp_text user "Author: Antmicro"
			(at -1.682 -4.894 0)
			(layer "B.Fab")
			(effects
				(font
					(size 0.7 0.7)
					(thickness 0.15)
				)
				(justify left bottom mirror)
			)
		)
		(fp_text user "License: Apache-2.0"
			(at -1.682 -5.895 0)
			(layer "B.Fab")
			(effects
				(font
					(size 0.7 0.7)
					(thickness 0.15)
				)
				(justify left bottom mirror)
			)
		)
		(pad "1" smd roundrect
			(at -0.7 0 180)
			(size 0.8 1)
			(layers "B.Cu" "B.Mask" "B.Paste")
			(roundrect_rratio 0.2)
			(net 1 "GND")
			(pintype "passive")
		)
		(pad "2" smd roundrect
			(at 0.7 0 180)
			(size 0.8 1)
			(layers "B.Cu" "B.Mask" "B.Paste")
			(roundrect_rratio 0.2)
			(net 10 "+12V")
			(pintype "passive")
		)
	)
	(footprint "antmicro-footprints:R_0402_1005Metric"
		(layer "B.Cu")
		(at 250.375 122.225)
		(descr "Resistor SMD 0402")
		(tags "resistor SMD 0402")
		(property "Reference" "R240"
			(at -1.4 1.625 0)
			(layer "B.SilkS")
			(effects
				(font
					(size 0.7 0.7)
					(thickness 0.15)
				)
				(justify right bottom mirror)
			)
		)
		(property "Value" "R_47k_0402"
			(at -1.011843 -1.772047 0)
			(layer "B.Fab")
			(effects
				(font
					(size 0.7 0.7)
					(thickness 0.15)
				)
				(justify right bottom mirror)
			)
		)
		(property "Datasheet" "https://www.bourns.com/docs/product-datasheets/cr.pdf"
			(at 0 0 0)
			(layer "F.Fab")
			(hide yes)
			(effects
				(font
					(size 1.27 1.27)
					(thickness 0.15)
				)
			)
		)
		(property "MPN" "CR0402-FX-4702GLF"
			(at 0 0 0)
			(unlocked yes)
			(layer "B.Fab")
			(hide yes)
			(effects
				(font
					(size 1 1)
					(thickness 0.15)
				)
				(justify mirror)
			)
		)
		(property "Manufacturer" "Bourns"
			(at 0 0 0)
			(unlocked yes)
			(layer "B.Fab")
			(hide yes)
			(effects
				(font
					(size 1 1)
					(thickness 0.15)
				)
				(justify mirror)
			)
		)
		(property "License" "Apache-2.0"
			(at 0 0 0)
			(unlocked yes)
			(layer "B.Fab")
			(hide yes)
			(effects
				(font
					(size 1 1)
					(thickness 0.15)
				)
				(justify mirror)
			)
		)
		(property "Author" "Antmicro"
			(at 0 0 0)
			(unlocked yes)
			(layer "B.Fab")
			(hide yes)
			(effects
				(font
					(size 1 1)
					(thickness 0.15)
				)
				(justify mirror)
			)
		)
		(property "Val" "47k"
			(at 0 0 0)
			(unlocked yes)
			(layer "B.Fab")
			(hide yes)
			(effects
				(font
					(size 1 1)
					(thickness 0.15)
				)
				(justify mirror)
			)
		)
		(property "Tolerance" "1%"
			(at 0 0 0)
			(unlocked yes)
			(layer "B.Fab")
			(hide yes)
			(effects
				(font
					(size 1 1)
					(thickness 0.15)
				)
				(justify mirror)
			)
		)
		(sheetname "/DDR5 RDIMM/")
		(sheetfile "ddr5-rdimm.kicad_sch")
		(attr smd)
		(fp_rect
			(start -0.925 0.47)
			(end 0.925 -0.47)
			(stroke
				(width 0.05)
				(type default)
			)
			(fill no)
			(layer "B.CrtYd")
		)
		(fp_rect
			(start -0.5 0.25)
			(end 0.5 -0.25)
			(stroke
				(width 0.15)
				(type solid)
			)
			(fill no)
			(layer "B.Fab")
		)
		(fp_text user "${REFERENCE}"
			(at -0.95 -3.168 180)
			(layer "B.Fab")
			(effects
				(font
					(size 0.7 0.7)
					(thickness 0.15)
				)
				(justify left bottom mirror)
			)
		)
		(fp_text user "Author: Antmicro"
			(at -0.95 -4.169 180)
			(layer "B.Fab")
			(effects
				(font
					(size 0.7 0.7)
					(thickness 0.15)
				)
				(justify left bottom mirror)
			)
		)
		(fp_text user "License: Apache-2.0"
			(at -0.95 -5.169 180)
			(layer "B.Fab")
			(effects
				(font
					(size 0.7 0.7)
					(thickness 0.15)
				)
				(justify left bottom mirror)
			)
		)
		(pad "1" smd roundrect
			(at -0.48 0)
			(size 0.59 0.64)
			(layers "B.Cu" "B.Mask" "B.Paste")
			(roundrect_rratio 0.25)
			(net 1 "GND")
			(pintype "passive")
		)
		(pad "2" smd roundrect
			(at 0.48 0)
			(size 0.59 0.64)
			(layers "B.Cu" "B.Mask" "B.Paste")
			(roundrect_rratio 0.25)
			(net 808 "VIN_BULK_EN")
			(pintype "passive")
		)
	)
	(footprint "antmicro-footprints:R_0402_1005Metric"
		(layer "B.Cu")
		(at 254.274499 132.199 90)
		(descr "Resistor SMD 0402")
		(tags "resistor SMD 0402")
		(property "Reference" "R149"
			(at 1.324 -0.599499 90)
			(layer "B.SilkS")
			(effects
				(font
					(size 0.7 0.7)
					(thickness 0.15)
				)
				(justify right bottom mirror)
			)
		)
		(property "Value" "R_47k_0402"
			(at -1.011843 -1.772047 90)
			(layer "B.Fab")
			(effects
				(font
					(size 0.7 0.7)
					(thickness 0.15)
				)
				(justify right bottom mirror)
			)
		)
		(property "Datasheet" "https://www.bourns.com/docs/product-datasheets/cr.pdf"
			(at 0 0 90)
			(layer "F.Fab")
			(hide yes)
			(effects
				(font
					(size 1.27 1.27)
					(thickness 0.15)
				)
			)
		)
		(property "Manufacturer" "Bourns"
			(at 0 0 90)
			(unlocked yes)
			(layer "B.Fab")
			(hide yes)
			(effects
				(font
					(size 1 1)
					(thickness 0.15)
				)
				(justify mirror)
			)
		)
		(property "MPN" "CR0402-FX-4702GLF"
			(at 0 0 90)
			(unlocked yes)
			(layer "B.Fab")
			(hide yes)
			(effects
				(font
					(size 1 1)
					(thickness 0.15)
				)
				(justify mirror)
			)
		)
		(property "Val" "47k"
			(at 0 0 90)
			(unlocked yes)
			(layer "B.Fab")
			(hide yes)
			(effects
				(font
					(size 1 1)
					(thickness 0.15)
				)
				(justify mirror)
			)
		)
		(property "License" "Apache-2.0"
			(at 0 0 90)
			(unlocked yes)
			(layer "B.Fab")
			(hide yes)
			(effects
				(font
					(size 1 1)
					(thickness 0.15)
				)
				(justify mirror)
			)
		)
		(property "Author" "Antmicro"
			(at 0 0 90)
			(unlocked yes)
			(layer "B.Fab")
			(hide yes)
			(effects
				(font
					(size 1 1)
					(thickness 0.15)
				)
				(justify mirror)
			)
		)
		(property "Tolerance" "1%"
			(at 0 0 90)
			(unlocked yes)
			(layer "B.Fab")
			(hide yes)
			(effects
				(font
					(size 1 1)
					(thickness 0.15)
				)
				(justify mirror)
			)
		)
		(sheetname "/Supply/")
		(sheetfile "supply.kicad_sch")
		(attr smd)
		(fp_rect
			(start -0.925 0.47)
			(end 0.925 -0.47)
			(stroke
				(width 0.05)
				(type default)
			)
			(fill no)
			(layer "B.CrtYd")
		)
		(fp_rect
			(start -0.5 0.25)
			(end 0.5 -0.25)
			(stroke
				(width 0.15)
				(type solid)
			)
			(fill no)
			(layer "B.Fab")
		)
		(fp_text user "License: Apache-2.0"
			(at -0.95 -5.169 270)
			(layer "B.Fab")
			(effects
				(font
					(size 0.7 0.7)
					(thickness 0.15)
				)
				(justify left bottom mirror)
			)
		)
		(fp_text user "${REFERENCE}"
			(at -0.95 -3.168 270)
			(layer "B.Fab")
			(effects
				(font
					(size 0.7 0.7)
					(thickness 0.15)
				)
				(justify left bottom mirror)
			)
		)
		(fp_text user "Author: Antmicro"
			(at -0.95 -4.169 270)
			(layer "B.Fab")
			(effects
				(font
					(size 0.7 0.7)
					(thickness 0.15)
				)
				(justify left bottom mirror)
			)
		)
		(pad "1" smd roundrect
			(at -0.48 0 90)
			(size 0.59 0.64)
			(layers "B.Cu" "B.Mask" "B.Paste")
			(roundrect_rratio 0.25)
			(net 137 "/Supply/~{PB_CTRL_CLR}")
			(pintype "passive")
		)
		(pad "2" smd roundrect
			(at 0.48 0 90)
			(size 0.59 0.64)
			(layers "B.Cu" "B.Mask" "B.Paste")
			(roundrect_rratio 0.25)
			(net 138 "/Supply/PB_CTRL_OUT")
			(pintype "passive")
		)
	)
	(footprint "antmicro-footprints:SOT-323"
		(layer "B.Cu")
		(at 247.05 183.399)
		(property "Reference" "Q22"
			(at -1.05 -1.6 0)
			(layer "B.SilkS")
			(effects
				(font
					(size 0.7 0.7)
					(thickness 0.15)
				)
				(justify right bottom mirror)
			)
		)
		(property "Value" "BSS84AKW"
			(at 0 -2.749 0)
			(layer "B.Fab")
			(effects
				(font
					(size 0.7 0.7)
					(thickness 0.15)
				)
				(justify right bottom mirror)
			)
		)
		(property "Datasheet" "https://assets.nexperia.com/documents/data-sheet/BSS84AKW.pdf"
			(at 0 0 0)
			(layer "F.Fab")
			(hide yes)
			(effects
				(font
					(size 1.27 1.27)
					(thickness 0.15)
				)
			)
		)
		(property "MPN" "BSS84AKW,115"
			(at 0 0 0)
			(unlocked yes)
			(layer "B.Fab")
			(hide yes)
			(effects
				(font
					(size 1 1)
					(thickness 0.15)
				)
				(justify mirror)
			)
		)
		(property "Manufacturer" "Nexperia"
			(at 0 0 0)
			(unlocked yes)
			(layer "B.Fab")
			(hide yes)
			(effects
				(font
					(size 1 1)
					(thickness 0.15)
				)
				(justify mirror)
			)
		)
		(property "Author" "Antmicro"
			(at 0 0 0)
			(unlocked yes)
			(layer "B.Fab")
			(hide yes)
			(effects
				(font
					(size 1 1)
					(thickness 0.15)
				)
				(justify mirror)
			)
		)
		(property "License" "Apache-2.0"
			(at 0 0 0)
			(unlocked yes)
			(layer "B.Fab")
			(hide yes)
			(effects
				(font
					(size 1 1)
					(thickness 0.15)
				)
				(justify mirror)
			)
		)
		(sheetname "/I^{2}C + I3C/")
		(sheetfile "i2c.kicad_sch")
		(attr smd)
		(fp_line
			(start -0.802 -1.199)
			(end -0.5 -1.199)
			(stroke
				(width 0.15)
				(type solid)
			)
			(layer "B.SilkS")
		)
		(fp_line
			(start -0.802 -1.05)
			(end -0.802 -1.199)
			(stroke
				(width 0.15)
				(type solid)
			)
			(layer "B.SilkS")
		)
		(fp_line
			(start -0.802 1.2)
			(end -0.802 1.05)
			(stroke
				(width 0.15)
				(type solid)
			)
			(layer "B.SilkS")
		)
		(fp_line
			(start -0.402 1.2)
			(end -0.802 1.2)
			(stroke
				(width 0.15)
				(type solid)
			)
			(layer "B.SilkS")
		)
		(fp_line
			(start 0.498 -1.199)
			(end 0.8 -1.199)
			(stroke
				(width 0.15)
				(type solid)
			)
			(layer "B.SilkS")
		)
		(fp_line
			(start 0.498 1.2)
			(end 0.8 1.2)
			(stroke
				(width 0.15)
				(type solid)
			)
			(layer "B.SilkS")
		)
		(fp_line
			(start 0.8 -1.199)
			(end 0.8 -0.9)
			(stroke
				(width 0.15)
				(type solid)
			)
			(layer "B.SilkS")
		)
		(fp_line
			(start 0.8 1.2)
			(end 0.8 0.902)
			(stroke
				(width 0.15)
				(type solid)
			)
			(layer "B.SilkS")
		)
		(fp_circle
			(center -1.05 1.156824)
			(end -1 1.129824)
			(stroke
				(width 0.15)
				(type solid)
			)
			(fill no)
			(layer "B.SilkS")
		)
		(fp_rect
			(start -1.35 1.35)
			(end 1.35 -1.35)
			(stroke
				(width 0.05)
				(type solid)
			)
			(fill no)
			(layer "B.CrtYd")
		)
		(fp_line
			(start -0.677 -1.1)
			(end 0.675 -1.1)
			(stroke
				(width 0.15)
				(type solid)
			)
			(layer "B.Fab")
		)
		(fp_line
			(start -0.677 1.101)
			(end -0.677 -1.1)
			(stroke
				(width 0.15)
				(type solid)
			)
			(layer "B.Fab")
		)
		(fp_line
			(start -0.677 1.101)
			(end 0.675 1.101)
			(stroke
				(width 0.15)
				(type solid)
			)
			(layer "B.Fab")
		)
		(fp_line
			(start 0.675 1.101)
			(end 0.675 -1.1)
			(stroke
				(width 0.15)
				(type solid)
			)
			(layer "B.Fab")
		)
		(fp_text user "Author: Antmicro"
			(at -1.35 -7.149 180)
			(layer "B.Fab")
			(effects
				(font
					(size 0.7 0.7)
					(thickness 0.15)
				)
				(justify left bottom mirror)
			)
		)
		(fp_text user "${REFERENCE}"
			(at -1.35 -4.749 180)
			(layer "B.Fab")
			(effects
				(font
					(size 0.7 0.7)
					(thickness 0.15)
				)
				(justify left bottom mirror)
			)
		)
		(fp_text user "License: Apache-2.0"
			(at -1.35 -5.949 180)
			(layer "B.Fab")
			(effects
				(font
					(size 0.7 0.7)
					(thickness 0.15)
				)
				(justify left bottom mirror)
			)
		)
		(pad "1" smd rect
			(at -0.927 0.652)
			(size 0.55 0.6)
			(layers "B.Cu" "B.Mask" "B.Paste")
			(net 778 "~{FPGA_I3C_EXT_PU}")
			(pinfunction "G")
			(pintype "bidirectional")
		)
		(pad "2" smd rect
			(at -0.927 -0.65)
			(size 0.55 0.6)
			(layers "B.Cu" "B.Mask" "B.Paste")
			(net 151 "+3V3")
			(pinfunction "S")
			(pintype "bidirectional")
		)
		(pad "3" smd rect
			(at 0.925 0)
			(size 0.55 0.6)
			(layers "B.Cu" "B.Mask" "B.Paste")
			(net 662 "Net-(Q22-D)")
			(pinfunction "D")
			(pintype "bidirectional")
		)
	)
	(footprint "antmicro-footprints:R_0402_1005Metric"
		(layer "B.Cu")
		(at 237.925 153.27 90)
		(descr "Resistor SMD 0402")
		(tags "resistor SMD 0402")
		(property "Reference" "R213"
			(at 0.97 0.475 90)
			(layer "B.SilkS")
			(effects
				(font
					(size 0.7 0.7)
					(thickness 0.15)
				)
				(justify right bottom mirror)
			)
		)
		(property "Value" "R_0R_0402"
			(at -1.011843 -1.772047 90)
			(layer "B.Fab")
			(effects
				(font
					(size 0.7 0.7)
					(thickness 0.15)
				)
				(justify right bottom mirror)
			)
		)
		(property "Datasheet" "https://industrial.panasonic.com/cdbs/www-data/pdf/RDA0000/AOA0000C301.pdf"
			(at 0 0 90)
			(layer "F.Fab")
			(hide yes)
			(effects
				(font
					(size 1.27 1.27)
					(thickness 0.15)
				)
			)
		)
		(property "MPN" "ERJ2GE0R00X"
			(at 0 0 90)
			(unlocked yes)
			(layer "B.Fab")
			(hide yes)
			(effects
				(font
					(size 1 1)
					(thickness 0.15)
				)
				(justify mirror)
			)
		)
		(property "Manufacturer" "Panasonic"
			(at 0 0 90)
			(unlocked yes)
			(layer "B.Fab")
			(hide yes)
			(effects
				(font
					(size 1 1)
					(thickness 0.15)
				)
				(justify mirror)
			)
		)
		(property "License" "Apache-2.0"
			(at 0 0 90)
			(unlocked yes)
			(layer "B.Fab")
			(hide yes)
			(effects
				(font
					(size 1 1)
					(thickness 0.15)
				)
				(justify mirror)
			)
		)
		(property "Author" "Antmicro"
			(at 0 0 90)
			(unlocked yes)
			(layer "B.Fab")
			(hide yes)
			(effects
				(font
					(size 1 1)
					(thickness 0.15)
				)
				(justify mirror)
			)
		)
		(property "Val" "0R"
			(at 0 0 90)
			(unlocked yes)
			(layer "B.Fab")
			(hide yes)
			(effects
				(font
					(size 1 1)
					(thickness 0.15)
				)
				(justify mirror)
			)
		)
		(property "Tolerance" "~"
			(at 0 0 90)
			(unlocked yes)
			(layer "B.Fab")
			(hide yes)
			(effects
				(font
					(size 1 1)
					(thickness 0.15)
				)
				(justify mirror)
			)
		)
		(property "Current" "1A"
			(at 0 0 90)
			(unlocked yes)
			(layer "B.Fab")
			(hide yes)
			(effects
				(font
					(size 1 1)
					(thickness 0.15)
				)
				(justify mirror)
			)
		)
		(sheetname "/Supply/DC-DC IO/")
		(sheetfile "dc-dc-io.kicad_sch")
		(attr smd)
		(fp_rect
			(start -0.925 0.47)
			(end 0.925 -0.47)
			(stroke
				(width 0.05)
				(type default)
			)
			(fill no)
			(layer "B.CrtYd")
		)
		(fp_rect
			(start -0.5 0.25)
			(end 0.5 -0.25)
			(stroke
				(width 0.15)
				(type solid)
			)
			(fill no)
			(layer "B.Fab")
		)
		(fp_text user "${REFERENCE}"
			(at -0.95 -3.168 270)
			(layer "B.Fab")
			(effects
				(font
					(size 0.7 0.7)
					(thickness 0.15)
				)
				(justify left bottom mirror)
			)
		)
		(fp_text user "License: Apache-2.0"
			(at -0.95 -5.169 270)
			(layer "B.Fab")
			(effects
				(font
					(size 0.7 0.7)
					(thickness 0.15)
				)
				(justify left bottom mirror)
			)
		)
		(fp_text user "Author: Antmicro"
			(at -0.95 -4.169 270)
			(layer "B.Fab")
			(effects
				(font
					(size 0.7 0.7)
					(thickness 0.15)
				)
				(justify left bottom mirror)
			)
		)
		(pad "1" smd roundrect
			(at -0.48 0 90)
			(size 0.59 0.64)
			(layers "B.Cu" "B.Mask" "B.Paste")
			(roundrect_rratio 0.25)
			(net 733 "Net-(U28-IN3+)")
			(pintype "passive")
		)
		(pad "2" smd roundrect
			(at 0.48 0 90)
			(size 0.59 0.64)
			(layers "B.Cu" "B.Mask" "B.Paste")
			(roundrect_rratio 0.25)
			(net 695 "/Supply/DC-DC IO/VDDQ_SEN_+")
			(pintype "passive")
		)
	)
)
